FILE_TYPE = CONNECTIVITY;
{Allegro Design Entry HDL 16.6-p007 (v16-6-112F) 10/10/2012}
"PAGE_NUMBER" = 56;
0"NC";
1"GND\g";
2"PVCCMCP_CPU1\g";
3"P1V8_MCP_CPU1\g";
4"TP_CPU1_RSVD_304";
5"TP_CPU1_RSVD_287";
6"TP_CPU1_RSVD_286";
7"TP_CPU1_RSVD_274";
8"TP_CPU1_RSVD_268";
9"TP_CPU1_RSVD_264";
10"TP_CPU1_RSVD_263";
11"TP_CPU1_RSVD_251";
12"TP_CPU1_RSVD_250";
13"TP_CPU1_RSVD_249";
14"TP_CPU1_RSVD_248";
15"TP_CPU1_RSVD_247";
16"TP_CPU1_RSVD_246";
17"TP_CPU1_RSVD_245";
18"TP_CPU1_RSVD_244";
19"TP_CPU1_RSVD_288";
20"TP_CPU1_RSVD_283";
21"TP_CPU1_RSVD_282";
22"TP_CPU1_RSVD_285";
23"TP_CPU1_RSVD_252";
24"TP_CPU1_RSVD_273";
25"TP_CPU1_RSVD_272";
26"TP_CPU1_RSVD_271";
27"TP_CPU1_RSVD_269";
28"TP_CPU1_RSVD_298";
29"TP_CPU1_RSVD_242";
30"TP_CPU1_RSVD_243";
31"TP_CPU1_RSVD_260";
32"TP_CPU1_RSVD_261";
33"TP_CPU1_RSVD_262";
34"TP_CPU1_RSVD_266";
35"TP_CPU1_RSVD_267";
36"TP_CPU1_RSVD_270";
37"TP_CPU1_RSVD_284";
38"TP_CPU1_RSVD_289";
39"TP_CPU1_RSVD_291";
40"TP_CPU1_RSVD_293";
41"TP_CPU1_RSVD_292";
42"TP_CPU1_RSVD_290";
43"TP_CPU1_RSVD_253";
44"TP_CPU1_RSVD_254";
45"TP_CPU1_RSVD_TEST_11";
46"TP_CPU1_RSVD_259";
47"TP_CPU1_RSVD_258";
48"TP_CPU1_RSVD_256";
49"TP_CPU1_RSVD_265";
50"TP_CPU1_RSVD_281";
51"TP_CPU1_RSVD_280";
52"TP_CPU1_RSVD_279";
53"TP_CPU1_RSVD_278";
54"TP_CPU1_RSVD_277";
55"TP_CPU1_RSVD_276";
56"TP_CPU1_RSVD_275";
57"FM_CPU1_RC_ERROR_N";
58"TP_CPU1_RSVD_303";
59"TP_CPU1_RSVD_299";
60"TP_CPU1_RSVD_300";
61"TP_CPU1_RSVD_TEST_5";
62"TP_CPU1_RSVD_216";
63"TP_CPU1_RSVD_212";
64"TP_CPU1_RSVD_211";
65"TP_CPU1_RSVD_210";
66"TP_CPU1_RSVD_208";
67"TP_CPU1_RSVD_214";
68"TP_CPU1_RSVD_217";
69"TP_CPU1_RSVD_218";
70"TP_CPU1_RSVD_219";
71"TP_CPU1_RSVD_222";
72"TP_CPU1_RSVD_223";
73"TP_CPU1_RSVD_224";
74"TP_CPU1_RSVD_225";
75"TP_CPU1_RSVD_226";
76"TP_CPU1_RSVD_227";
77"TP_CPU1_RSVD_228";
78"TP_CPU1_RSVD_229";
79"TP_CPU1_RSVD_230";
80"TP_CPU1_RSVD_231";
81"TP_CPU1_RSVD_232";
82"TP_CPU1_RSVD_233";
83"TP_CPU1_RSVD_234";
84"TP_CPU1_RSVD_235";
85"TP_CPU1_RSVD_194";
86"TP_CPU1_RSVD_198";
87"TP_CPU1_RSVD_199";
88"TP_CPU1_RSVD_204";
89"TP_CPU1_RSVD_205";
90"TP_CPU1_RSVD_TEST_4";
91"TP_CPU1_RSVD_TEST_3";
92"XDP_CPU_PWR_DEBUG_N";
93"XDP_PRESENT_N";
94"CLK_100M_CPU1_RC_REFCLK0_DP";
95"CLK_100M_CPU1_RC_REFCLK0_DN";
96"CLK_322M_OSC_CPU1_RC_DN";
97"PD_CPU1_DMIMODE_OVERRIDE";
98"CLK_322M_OSC_CPU1_RC_DP";
99"H_CPU1_FIVR_FAULT_G";
100"VSENSE_P1V8MCP_CPU1_SKT_VSEN";
101"VSENSE_P1V8MCP_CPU1_SKT_VRTN";
102"PD_CPU1_RSVD_TEST_2";
103"PD_CPU1_RSVD_TEST_1";
104"TP_CPU1_RSVD_236";
105"TP_CPU1_RSVD_237";
106"TP_CPU1_RSVD_238";
107"TP_CPU1_RSVD_239";
108"TP_CPU1_RSVD_240";
109"TP_CPU1_RSVD_241";
%"SKX_EXT_B"
"2","(-4025,2550)","0","chpset_lib","I169";
;
CDS_SEC"2"
CDS_LOCATION"U2D1"
SEC"2"
SEC_TYPE"BGA1"
CDS_LIB"chpset_lib"
PACK_TYPE"BGA1"
MATERIAL"IC"
PART_NUMBER"TBD"
LOCATION"U2D1";
"TEST_5"
$PN"AN14"61;
"TEST_4"
$PN"AN12"90;
"TEST_3"
$PN"AM13"91;
"TEST_2"
$PN"AG46"102;
"TEST_11"
$PN"AY13"45;
"TEST_1"
$PN"AF45"103;
"RSVD<194>"
$PN"AP61"85;
"RSVD<195>"
$PN"AP27"95;
"RSVD<196>"
$PN"AP25"2;
"RSVD<197>"
$PN"AP23"2;
"RSVD<198>"
$PN"AN62"86;
"RSVD<199>"
$PN"AN60"87;
"RSVD<200>"
$PN"AN26"2;
"RSVD<201>"
$PN"AN24"2;
"RSVD<202>"
$PN"AN22"2;
"RSVD<203>"
$PN"AN18"2;
"RSVD<204>"
$PN"AM61"88;
"RSVD<205>"
$PN"AM59"89;
"RSVD<206>"
$PN"AM27"94;
"RSVD<207>"
$PN"AM25"2;
"RSVD<208>"
$PN"AM23"66;
"RSVD<209>"
$PN"AM21"2;
"RSVD<210>"
$PN"AL62"65;
"RSVD<211>"
$PN"AL60"64;
"RSVD<212>"
$PN"AL58"63;
"RSVD<213>"
$PN"AL26"96;
"RSVD<214>"
$PN"AL22"67;
"RSVD<215>"
$PN"AL20"101;
"RSVD<216>"
$PN"AK69"62;
"RSVD<217>"
$PN"AK61"68;
"RSVD<218>"
$PN"AK59"69;
"RSVD<219>"
$PN"AK57"70;
"RSVD<220>"
$PN"AK27"98;
"RSVD<221>"
$PN"AK21"100;
"RSVD<222>"
$PN"AJ70"71;
"RSVD<223>"
$PN"AJ62"72;
"RSVD<224>"
$PN"AJ60"73;
"RSVD<225>"
$PN"AJ58"74;
"RSVD<226>"
$PN"AJ56"75;
"RSVD<227>"
$PN"AJ20"76;
"RSVD<228>"
$PN"AH73"77;
"RSVD<229>"
$PN"AH71"78;
"RSVD<230>"
$PN"AH57"79;
"RSVD<231>"
$PN"AH55"80;
"RSVD<232>"
$PN"AH19"81;
"RSVD<233>"
$PN"AH15"82;
"RSVD<234>"
$PN"AG72"83;
"RSVD<235>"
$PN"AG56"84;
"RSVD<236>"
$PN"AG54"104;
"RSVD<237>"
$PN"AG52"105;
"RSVD<238>"
$PN"AG50"106;
"RSVD<239>"
$PN"AG48"107;
"RSVD<240>"
$PN"AG20"108;
"RSVD<241>"
$PN"AF71"109;
"RSVD<242>"
$PN"AF53"29;
"RSVD<243>"
$PN"AF51"30;
"RSVD<244>"
$PN"AF49"18;
"RSVD<245>"
$PN"AF47"17;
"RSVD<246>"
$PN"AF19"16;
"RSVD<247>"
$PN"AE72"15;
"RSVD<248>"
$PN"AE52"14;
"RSVD<249>"
$PN"AE50"13;
"RSVD<250>"
$PN"AE48"12;
"RSVD<251>"
$PN"AE46"11;
"RSVD<252>"
$PN"AD51"23;
"RSVD<253>"
$PN"AD49"43;
"RSVD<254>"
$PN"AD47"44;
"RSVD<256>"
$PN"Y65"48;
"RSVD<257>"
$PN"Y23"57;
"RSVD<258>"
$PN"W66"47;
"RSVD<259>"
$PN"V67"46;
"RSVD<260>"
$PN"V65"31;
"RSVD<261>"
$PN"U66"32;
"RSVD<262>"
$PN"T67"33;
"RSVD<263>"
$PN"R66"10;
"RSVD<264>"
$PN"R62"9;
"RSVD<265>"
$PN"P65"49;
"RSVD<266>"
$PN"M63"34;
"RSVD<267>"
$PN"K61"35;
"RSVD<268>"
$PN"J62"8;
"RSVD<269>"
$PN"J46"27;
"RSVD<270>"
$PN"H85"36;
"RSVD<271>"
$PN"H83"26;
"RSVD<272>"
$PN"H1"25;
"RSVD<273>"
$PN"G84"24;
"RSVD<274>"
$PN"G64"7;
"RSVD<275>"
$PN"G2"56;
"RSVD<276>"
$PN"F83"55;
"RSVD<277>"
$PN"F65"54;
"RSVD<278>"
$PN"F23"53;
"RSVD<279>"
$PN"F3"52;
"RSVD<280>"
$PN"E84"51;
"RSVD<281>"
$PN"E24"50;
"RSVD<282>"
$PN"E4"21;
"RSVD<283>"
$PN"E2"20;
"RSVD<284>"
$PN"D83"37;
"RSVD<285>"
$PN"D65"22;
"RSVD<286>"
$PN"D17"6;
"RSVD<287>"
$PN"D5"5;
"RSVD<288>"
$PN"C82"19;
"RSVD<289>"
$PN"C24"38;
"RSVD<290>"
$PN"C18"42;
"RSVD<291>"
$PN"C6"39;
"RSVD<292>"
$PN"B81"41;
"RSVD<293>"
$PN"B77"40;
"RSVD<294>"
$PN"B17"3;
"RSVD<295>"
$PN"B15"3;
"RSVD<296>"
$PN"B13"3;
"RSVD<298>"
$PN"B7"28;
"RSVD<299>"
$PN"B3"59;
"RSVD<300>"
$PN"A24"60;
"RSVD<301>"
$PN"A16"3;
"RSVD<302>"
$PN"A14"3;
"RSVD<303>"
$PN"A6"58;
"RSVD<304>"
$PN"A4"4;
"PWR_DEBUG_N"
$PN"AP17"92;
"FIVR_FAULT"
$PN"AU14"99;
"DMIMODE_OVERRIDE"
$PN"AW12"97;
"DEBUG_EN_N"
$PN"AV21"93;
%"GND"
"1","(-275,2425)","0","mstr_symbols","I171";
;
HDL_POWER"GND"
BODY_TYPE"PLUMBING"
CDS_LIB"mstr_symbols"
SIZE"1B"
VOLTAGE"0.0V";
"A\NAC"1;
%"RES"
"2","(-550,2750)","0","mstr_discrete","I173";
;
CDS_SEC"1"
ROOM"CPU1"
CDS_LOCATION"R8P3"
SEC"1"
CDS_LIB"mstr_discrete"
SEC_TYPE"0402"
WATTAGE"1/16W"
MATERIAL"CHIP"
PACK_TYPE"0402"
TOLERANCE"1%"
VALUE"49.9"
PART_NUMBER"G21796-047"
LOCATION"R8P3";
"A"
$PN"1"102;
"B"
$PN"2"1;
%"RES"
"2","(-275,2750)","0","mstr_discrete","I174";
;
CDS_SEC"1"
ROOM"CPU1"
CDS_LOCATION"R8R1"
SEC"1"
SEC_TYPE"0402"
CDS_LIB"mstr_discrete"
WATTAGE"1/16W"
MATERIAL"CHIP"
PACK_TYPE"0402"
TOLERANCE"1%"
VALUE"49.9"
PART_NUMBER"G21796-047"
LOCATION"R8R1";
"A"
$PN"1"103;
"B"
$PN"2"1;
%"VCC_CORE"
"1","(-950,2325)","0","mstr_symbols","I185";
;
CDS_LIB"mstr_symbols"
HDL_POWER"PVCCMCP_CPU1";
"A"2;
%"VCC_CORE"
"1","(-7250,4350)","0","mstr_symbols","I188";
;
CDS_LIB"mstr_symbols"
VOLTAGE"1.8"
HDL_POWER"P1V8_MCP_CPU1";
"A"3;
END.
